# TIMECARD (Time Appliance Project (Time Card)) — schematic netlist excerpt (pin names and nets, part order shuffled) for the footprints in the layout excerpt that follows; sources: Cadence DE-HDL packaged netlist, KiCad conversion of R4006-B0001-02_R01.brd

R480  RESISTOR  100KOHM 1%  pkg SMC_0402R_H016  page 24 : \1\ = UART_FT4232_TX_FPGA_RX ; \2\ = XP3R3V_FT4232
TP57  TP_PIONT  pkg TP010CT020B030_PTH  page 25 : \1\ = XP2R5V_FPGA

(kicad_pcb
	(version 20260206)
	(generator "pcbnew")
	(generator_version "10.0")
	(general
		(thickness 1.6)
		(legacy_teardrops no)
	)
	(paper "A4")
	(title_block
		(title "timecard-production-celestica-r4006 — R4006-B0001-02_R01.brd")
		(comment 1 "Time Appliance Project (Time Card) / footprints 179-180 of 1113")
	)
	(layers
		(0 "F.Cu" signal "TOP")
		(4 "In1.Cu" signal "L02_GND1")
		(6 "In2.Cu" signal "L03_SIG1")
		(8 "In3.Cu" signal "L04_GND2")
		(10 "In4.Cu" signal "L05_VCC1")
		(12 "In5.Cu" signal "L06_VCC2")
		(14 "In6.Cu" signal "L07_GND3")
		(16 "In7.Cu" signal "L08_SIG2")
		(18 "In8.Cu" signal "L09_GND4")
		(2 "B.Cu" signal "BOTTOM")
		(9 "F.Adhes" user "F.Adhesive")
		(11 "B.Adhes" user "B.Adhesive")
		(13 "F.Paste" user "Package Geometry/Pastemask Top")
		(15 "B.Paste" user "Package Geometry/Pastemask Bottom")
		(5 "F.SilkS" user "Ref Des/Silkscreen Top")
		(7 "B.SilkS" user "Ref Des/Silkscreen Bottom")
		(1 "F.Mask" user "Board Geometry/Soldermask Top")
		(3 "B.Mask" user "Board Geometry/Soldermask Bottom")
		(17 "Dwgs.User" user "User.Drawings")
		(19 "Cmts.User" user "User.Comments")
		(21 "Eco1.User" user "User.Eco1")
		(23 "Eco2.User" user "User.Eco2")
		(25 "Edge.Cuts" user "Board Geometry/Outline")
		(27 "Margin" user)
		(31 "F.CrtYd" user "Package Geometry/Place Bound Top")
		(29 "B.CrtYd" user "Package Geometry/Place Bound Bottom")
		(35 "F.Fab" user "Ref Des/Assembly Top")
		(33 "B.Fab" user "Ref Des/Assembly Bottom")
	)
	(footprint ""
		(layer "F.Cu")
		(at 138.303 -20.193)
		(property "Reference" "TP57"
			(at -2.6162 1.43637 0)
			(unlocked yes)
			(layer "F.SilkS")
			(effects
				(font
					(size 0.7874 0.5842)
					(thickness 0.1524)
				)
				(justify left)
			)
		)
		(property "Value" ""
			(at 0 0 0)
			(layer "F.Fab")
			(effects
				(font
					(size 1.27 1.27)
				)
			)
		)
		(property "Device Type" "TP_PIONT-TP010CT020B030_PTH-TPA"
			(at -1.341882 0.996696 0)
			(unlocked yes)
			(layer "F.Fab")
			(hide yes)
			(effects
				(font
					(size 0.7874 0.5842)
					(thickness 0.1524)
				)
				(justify left)
			)
		)
		(duplicate_pad_numbers_are_jumpers no)
		(fp_poly
			(pts
				(arc
					(start 0.889 0)
					(mid -0.889 0)
					(end 0.889 0)
				)
			)
			(stroke
				(width 0)
				(type default)
			)
			(fill no)
			(layer "B.CrtYd")
		)
		(fp_poly
			(pts
				(arc
					(start 0.889 0)
					(mid -0.889 0)
					(end 0.889 0)
				)
			)
			(stroke
				(width 0)
				(type default)
			)
			(fill no)
			(layer "F.CrtYd")
		)
		(pad "1" thru_hole circle
			(at 0 0)
			(size 0.508 0.508)
			(drill 0.254)
			(layers "*.Cu" "*.Mask")
			(remove_unused_layers no)
			(net "XP2R5V_FPGA")
			(clearance 0.1016)
			(padstack
				(mode front_inner_back)
				(layer "Inner"
					(shape circle)
					(size 0.508 0.508)
					(clearance 0.1016)
				)
				(layer "B.Cu"
					(shape circle)
					(size 0.762 0.762)
					(clearance -0.0254)
				)
			)
		)
	)
	(footprint ""
		(layer "F.Cu")
		(at 26.035 -75.184 90)
		(property "Reference" "R480"
			(at -3.175 0.54737 90)
			(unlocked yes)
			(layer "F.SilkS")
			(effects
				(font
					(size 0.7874 0.5842)
					(thickness 0.1524)
				)
			)
		)
		(property "Value" "VAL*"
			(at 0.02032 2.13233 90)
			(unlocked yes)
			(layer "F.Fab")
			(hide yes)
			(effects
				(font
					(size 0.7874 0.5842)
					(thickness 0.1524)
				)
			)
		)
		(property "Tolerance" "TOL*"
			(at 0.044704 3.05435 90)
			(unlocked yes)
			(layer "Cmts.User")
			(hide yes)
			(effects
				(font
					(size 0.7874 0.5842)
					(thickness 0.1524)
				)
			)
		)
		(property "User Part Number" "PARTNUM*"
			(at 0.02032 4.024884 90)
			(unlocked yes)
			(layer "Cmts.User")
			(hide yes)
			(effects
				(font
					(size 0.7874 0.5842)
					(thickness 0.1524)
				)
			)
		)
		(property "Device Type" "RESISTOR-G155-11003-01,100KOHMA"
			(at 0.008382 1.210564 90)
			(unlocked yes)
			(layer "F.Fab")
			(hide yes)
			(effects
				(font
					(size 0.7874 0.5842)
					(thickness 0.1524)
				)
			)
		)
		(duplicate_pad_numbers_are_jumpers no)
		(fp_line
			(start 1.143 -0.5588)
			(end -1.143 -0.5588)
			(stroke
				(width 0.1)
				(type default)
			)
			(layer "F.SilkS")
		)
		(fp_line
			(start -1.143 -0.5588)
			(end -1.143 0.5588)
			(stroke
				(width 0.1)
				(type default)
			)
			(layer "F.SilkS")
		)
		(fp_line
			(start 1.143 0.5588)
			(end 1.143 -0.5588)
			(stroke
				(width 0.1)
				(type default)
			)
			(layer "F.SilkS")
		)
		(fp_line
			(start -1.143 0.5588)
			(end 1.143 0.5588)
			(stroke
				(width 0.1)
				(type default)
			)
			(layer "F.SilkS")
		)
		(fp_poly
			(pts
				(xy -1.143 0.5588) (xy 1.143 0.5588) (xy 1.143 -0.5588) (xy -1.143 -0.5588)
			)
			(stroke
				(width 0)
				(type default)
			)
			(fill no)
			(layer "F.CrtYd")
		)
		(fp_line
			(start 0.508 -0.3048)
			(end -0.508 -0.3048)
			(stroke
				(width 0.1)
				(type default)
			)
			(layer "F.Fab")
		)
		(fp_line
			(start -0.508 -0.3048)
			(end -0.508 0.3048)
			(stroke
				(width 0.1)
				(type default)
			)
			(layer "F.Fab")
		)
		(fp_line
			(start 0.508 0.3048)
			(end 0.508 -0.3048)
			(stroke
				(width 0.1)
				(type default)
			)
			(layer "F.Fab")
		)
		(fp_line
			(start -0.508 0.3048)
			(end 0.508 0.3048)
			(stroke
				(width 0.1)
				(type default)
			)
			(layer "F.Fab")
		)
		(pad "1" smd rect
			(at -0.5334 0 90)
			(size 0.7112 0.6096)
			(layers "F.Cu" "F.Mask" "F.Paste")
			(net "UART_FT4232_TX_FPGA_RX")
		)
		(pad "2" smd rect
			(at 0.5334 0 90)
			(size 0.7112 0.6096)
			(layers "F.Cu" "F.Mask" "F.Paste")
			(net "XP3R3V_FT4232")
		)
		(zone
			(layer "F.Cu")
			(hatch none 0.5)
			(connect_pads
				(clearance 0)
			)
			(min_thickness 0.25)
			(keepout
				(tracks allowed)
				(vias not_allowed)
				(pads allowed)
				(copperpour not_allowed)
				(footprints allowed)
			)
			(placement
				(enabled no)
				(sheetname "")
			)
			(fill
				(thermal_gap 0.5)
				(thermal_bridge_width 0.5)
				(island_removal_mode 0)
			)
			(polygon
				(pts
					(xy 26.3398 -75.1078) (xy 26.3398 -75.2602) (xy 25.7302 -75.2602) (xy 25.7302 -75.1078)
				)
			)
		)
		(zone
			(layer "F.Cu")
			(hatch none 0.5)
			(connect_pads
				(clearance 0)
			)
			(min_thickness 0.25)
			(keepout
				(tracks not_allowed)
				(vias allowed)
				(pads allowed)
				(copperpour not_allowed)
				(footprints allowed)
			)
			(placement
				(enabled no)
				(sheetname "")
			)
			(fill
				(thermal_gap 0.5)
				(thermal_bridge_width 0.5)
				(island_removal_mode 0)
			)
			(polygon
				(pts
					(xy 26.3398 -75.1078) (xy 26.3398 -75.2602) (xy 25.7302 -75.2602) (xy 25.7302 -75.1078)
				)
			)
		)
	)
)
